# S9S_MB_2U (Grand Teton) — schematic netlist excerpt (pin names and nets, part order shuffled) for the footprints in the layout excerpt that follows; sources: Cadence DE-HDL packaged netlist, KiCad conversion of 03242023_DA0F0TMBIJ0_F0T_Motherboard_J_brd_V01_OCP.brd

PR4700  Q_RES  0 5% EMPTY  pkg 0402LF  page 300 : A = PVNN_MAIN_CPU1_FB_RC ; B = PVNN_MAIN_CPU1
R3943  Q_RES  0 5% CHIP  pkg 0402LF  page 193 : A = E1S_0_EN ; B = P12V_E1S_EN_0_R2

(kicad_pcb
	(version 20260206)
	(generator "pcbnew")
	(generator_version "10.0")
	(general
		(thickness 1.6)
		(legacy_teardrops no)
	)
	(paper "A4")
	(title_block
		(title "03242023_DA0F0TMBIJ0_F0T_Motherboard_J_brd_V01_OCP.brd")
		(comment 1 "Grand Teton / footprints 2291-2292 of 6105")
	)
	(layers
		(0 "F.Cu" signal "TOP")
		(4 "In1.Cu" signal "GND")
		(6 "In2.Cu" signal "IN1")
		(8 "In3.Cu" signal "GND1")
		(10 "In4.Cu" signal "IN2")
		(12 "In5.Cu" signal "GND2")
		(14 "In6.Cu" signal "IN3")
		(16 "In7.Cu" signal "GND3")
		(18 "In8.Cu" signal "VCC")
		(20 "In9.Cu" signal "VCC1")
		(22 "In10.Cu" signal "GND4")
		(24 "In11.Cu" signal "IN4")
		(26 "In12.Cu" signal "GND5")
		(28 "In13.Cu" signal "IN5")
		(30 "In14.Cu" signal "GND6")
		(32 "In15.Cu" signal "IN6")
		(34 "In16.Cu" signal "GND7")
		(2 "B.Cu" signal "BOTTOM")
		(9 "F.Adhes" user "F.Adhesive")
		(11 "B.Adhes" user "B.Adhesive")
		(13 "F.Paste" user "Package Geometry/Pastemask Top")
		(15 "B.Paste" user "Package Geometry/Pastemask Bottom")
		(5 "F.SilkS" user "Ref Des/Silkscreen Top")
		(7 "B.SilkS" user "Ref Des/Silkscreen Bottom")
		(1 "F.Mask" user "Board Geometry/Soldermask Top")
		(3 "B.Mask" user "Board Geometry/Soldermask Bottom")
		(17 "Dwgs.User" user "User.Drawings")
		(19 "Cmts.User" user "User.Comments")
		(21 "Eco1.User" user "User.Eco1")
		(23 "Eco2.User" user "User.Eco2")
		(25 "Edge.Cuts" user "Board Geometry/Outline")
		(27 "Margin" user)
		(31 "F.CrtYd" user "Package Geometry/Place Bound Top")
		(29 "B.CrtYd" user "Package Geometry/Place Bound Bottom")
		(35 "F.Fab" user "Ref Des/Assembly Top")
		(33 "B.Fab" user "Ref Des/Assembly Bottom")
	)
	(footprint ""
		(layer "F.Cu")
		(at 258.21386 -48.304704 180)
		(property "Reference" "R3943"
			(at 0 0 180)
			(layer "F.SilkS")
			(hide yes)
			(effects
				(font
					(size 1.27 1.27)
				)
			)
		)
		(property "Value" ""
			(at 0 0 180)
			(layer "F.Fab")
			(effects
				(font
					(size 1.27 1.27)
				)
			)
		)
		(duplicate_pad_numbers_are_jumpers no)
		(fp_line
			(start 0.7874 0.4064)
			(end -0.7874 0.4064)
			(stroke
				(width 0.1524)
				(type default)
			)
			(layer "F.SilkS")
		)
		(fp_line
			(start 0.7874 -0.4064)
			(end 0.7874 0.4064)
			(stroke
				(width 0.1524)
				(type default)
			)
			(layer "F.SilkS")
		)
		(fp_line
			(start -0.7874 0.4064)
			(end -0.7874 -0.4064)
			(stroke
				(width 0.1524)
				(type default)
			)
			(layer "F.SilkS")
		)
		(fp_line
			(start -0.7874 -0.4064)
			(end 0.7874 -0.4064)
			(stroke
				(width 0.1524)
				(type default)
			)
			(layer "F.SilkS")
		)
		(fp_line
			(start 0.67945 0.3048)
			(end 0.120396 0.3048)
			(stroke
				(width 0.1)
				(type default)
			)
			(layer "F.Fab")
		)
		(fp_line
			(start 0.67945 -0.3048)
			(end 0.67945 0.3048)
			(stroke
				(width 0.1)
				(type default)
			)
			(layer "F.Fab")
		)
		(fp_line
			(start 0.12065 -0.2794)
			(end 0.12065 -0.3048)
			(stroke
				(width 0.1)
				(type default)
			)
			(layer "F.Fab")
		)
		(fp_line
			(start 0.12065 -0.3048)
			(end 0.67945 -0.3048)
			(stroke
				(width 0.1)
				(type default)
			)
			(layer "F.Fab")
		)
		(fp_line
			(start 0.120396 0.3048)
			(end 0.120396 0.2794)
			(stroke
				(width 0.1)
				(type default)
			)
			(layer "F.Fab")
		)
		(fp_line
			(start 0.120396 0.2794)
			(end -0.12065 0.2794)
			(stroke
				(width 0.1)
				(type default)
			)
			(layer "F.Fab")
		)
		(fp_line
			(start -0.12065 0.3048)
			(end -0.67945 0.3048)
			(stroke
				(width 0.1)
				(type default)
			)
			(layer "F.Fab")
		)
		(fp_line
			(start -0.12065 0.2794)
			(end -0.12065 0.3048)
			(stroke
				(width 0.1)
				(type default)
			)
			(layer "F.Fab")
		)
		(fp_line
			(start -0.12065 -0.2794)
			(end 0.12065 -0.2794)
			(stroke
				(width 0.1)
				(type default)
			)
			(layer "F.Fab")
		)
		(fp_line
			(start -0.12065 -0.305054)
			(end -0.12065 -0.2794)
			(stroke
				(width 0.1)
				(type default)
			)
			(layer "F.Fab")
		)
		(fp_line
			(start -0.67945 0.3048)
			(end -0.67945 -0.305054)
			(stroke
				(width 0.1)
				(type default)
			)
			(layer "F.Fab")
		)
		(fp_line
			(start -0.67945 -0.305054)
			(end -0.12065 -0.305054)
			(stroke
				(width 0.1)
				(type default)
			)
			(layer "F.Fab")
		)
		(pad "1" smd circle
			(at -0.40005 0 180)
			(size 0 0)
			(layers "F.Cu" "F.Mask" "F.Paste")
			(net "E1S_0_EN")
		)
		(pad "2" smd circle
			(at 0.40005 0 180)
			(size 0 0)
			(layers "F.Cu" "F.Mask" "F.Paste")
			(net "P12V_E1S_EN_0_R2")
		)
	)
	(footprint ""
		(layer "F.Cu")
		(at 24.777446 -174.51451 90)
		(property "Reference" "PR4700"
			(at 0 0 90)
			(layer "F.SilkS")
			(hide yes)
			(effects
				(font
					(size 1.27 1.27)
				)
			)
		)
		(property "Value" ""
			(at 0 0 90)
			(layer "F.Fab")
			(effects
				(font
					(size 1.27 1.27)
				)
			)
		)
		(duplicate_pad_numbers_are_jumpers no)
		(fp_line
			(start 0.7874 -0.4064)
			(end 0.7874 0.4064)
			(stroke
				(width 0.1524)
				(type default)
			)
			(layer "F.SilkS")
		)
		(fp_line
			(start -0.7874 -0.4064)
			(end 0.7874 -0.4064)
			(stroke
				(width 0.1524)
				(type default)
			)
			(layer "F.SilkS")
		)
		(fp_line
			(start 0.7874 0.4064)
			(end -0.7874 0.4064)
			(stroke
				(width 0.1524)
				(type default)
			)
			(layer "F.SilkS")
		)
		(fp_line
			(start -0.7874 0.4064)
			(end -0.7874 -0.4064)
			(stroke
				(width 0.1524)
				(type default)
			)
			(layer "F.SilkS")
		)
		(fp_line
			(start -0.12065 -0.305054)
			(end -0.12065 -0.2794)
			(stroke
				(width 0.1)
				(type default)
			)
			(layer "F.Fab")
		)
		(fp_line
			(start -0.67945 -0.305054)
			(end -0.12065 -0.305054)
			(stroke
				(width 0.1)
				(type default)
			)
			(layer "F.Fab")
		)
		(fp_line
			(start 0.67945 -0.3048)
			(end 0.67945 0.3048)
			(stroke
				(width 0.1)
				(type default)
			)
			(layer "F.Fab")
		)
		(fp_line
			(start 0.12065 -0.3048)
			(end 0.67945 -0.3048)
			(stroke
				(width 0.1)
				(type default)
			)
			(layer "F.Fab")
		)
		(fp_line
			(start 0.12065 -0.2794)
			(end 0.12065 -0.3048)
			(stroke
				(width 0.1)
				(type default)
			)
			(layer "F.Fab")
		)
		(fp_line
			(start -0.12065 -0.2794)
			(end 0.12065 -0.2794)
			(stroke
				(width 0.1)
				(type default)
			)
			(layer "F.Fab")
		)
		(fp_line
			(start 0.120396 0.2794)
			(end -0.12065 0.2794)
			(stroke
				(width 0.1)
				(type default)
			)
			(layer "F.Fab")
		)
		(fp_line
			(start -0.12065 0.2794)
			(end -0.12065 0.3048)
			(stroke
				(width 0.1)
				(type default)
			)
			(layer "F.Fab")
		)
		(fp_line
			(start 0.67945 0.3048)
			(end 0.120396 0.3048)
			(stroke
				(width 0.1)
				(type default)
			)
			(layer "F.Fab")
		)
		(fp_line
			(start 0.120396 0.3048)
			(end 0.120396 0.2794)
			(stroke
				(width 0.1)
				(type default)
			)
			(layer "F.Fab")
		)
		(fp_line
			(start -0.12065 0.3048)
			(end -0.67945 0.3048)
			(stroke
				(width 0.1)
				(type default)
			)
			(layer "F.Fab")
		)
		(fp_line
			(start -0.67945 0.3048)
			(end -0.67945 -0.305054)
			(stroke
				(width 0.1)
				(type default)
			)
			(layer "F.Fab")
		)
		(pad "1" smd circle
			(at -0.40005 0 90)
			(size 0 0)
			(layers "F.Cu" "F.Mask" "F.Paste")
			(net "PVNN_MAIN_CPU1_FB_RC")
		)
		(pad "2" smd circle
			(at 0.40005 0 90)
			(size 0 0)
			(layers "F.Cu" "F.Mask" "F.Paste")
			(net "PVNN_MAIN_CPU1")
		)
	)
)
